# BASEBOARD_FAB2 (Tioga Pass) — schematic netlist excerpt (pin names and nets, part order shuffled) for the footprints in the layout excerpt that follows; sources: Cadence DE-HDL packaged netlist, KiCad conversion of Wiwynn_Tioga_Pass_MB.brd

U8D7  LCMXO2_A  IC  pkg 256BGA  page 190
  VCC(0)  = P3V3_STBY
  NC(0)  = NC
  PT11C  = FM_PCH_PRSNT_N
  PT10A  = FM_P3V3_CPLD_EN
  PT11A  = TP_CPLD1_PT11A
  PT12D_TDI  = JTAG_PLD_TDI
  PT16C_TCK  = JTAG_PLD_TCK
  PT17B_PCLKC0_1  = TP_CPLD1_PT17B_PCLKC0_1
  PT18C_SCL_PCLKT0_0  = SMB_SENSOR_STBY_LVC3_SCL
  PT19B  = FM_PVCCIN_PVCCSA_CPU0_EN_LVC1
  PT21A  = FM_CPU0_OR_CPU1_MCP_PRES
  PT22B  = PU_THERMTRIP_FORCE_N
  PT24C_INITN  = TP_CPLD1_PT24C_INITN
  PT22D  = TP_CPLD1_PT22D
  PT24B  = TP_CPLD1_PT24B
  VCC(1)  = P3V3_STBY
  PL1C  = RST_PCIE_PCH_PERST_N
  GND(0)  = GND
  PT9C  = FM_CTNR_PS_ON
  PT11D  = PWRGD_PVTT_CPU0
  PT9B  = PWRGD_P12V_MAIN
  PT11B  = TP_CPLD1_PT11B
  PT13A  = TP_CPLD1_PT13A
  PT16D_TMS  = JTAG_PLD_TMS
  PT19A  = PU_RST_PERST_BIT1
  PT20D_PROGRAMN  = PU_CPLD1_PT20D_PROGRAMN
  PT22A  = PWRGD_DSW_PWROK
  PT23B  = FM_PCH_PWRBTN_R1_N
  PT22C  = TP_CPLD1_PT22C
  PT24A  = FM_SINT_PRSNT_N
  GND(1)  = GND
  PR1D  = FM_ADR_COMPLETE_DLY
  PL2C  = RST_PCIE_CPU_DEV1_N
  PL1D  = FM_PCH_PLD_DATA
  GND(2)  = GND
  PT9A  = FM_ADR_SMI_GPIO_R_N
  PT10B  = FM_CPU1_THERMTRIP_LATCH_LVT3_N
  PT12C_TDO  = JTAG_PLD_TDO
  PT13B  = FM_BMC_ONCTL_N
  PT17A_PCLKT0_1  = FM_ADR_COMPLETE
  PT18D_SDA_PCLKC0_0  = SMB_SENSOR_STBY_LVC3_SDA
  PT20C_JTAGENB  = FM_JTAG_PLD_EN_DEBUG
  PT21B  = FM_CPU0_CD_PRES
  PT23A  = FM_SLPS4_N
  PT24D_DONE  = TP_CPLD1_PT24D_DONE
  GND(3)  = GND
  PR1C  = FM_DB1200_PWRGD
  PR2C  = PWRGD_PCH_PWROK
  PL1B_L_GPLLC_FB  = TP_CPLD1_PL1B_L_GPLLC_FB
  PL2D  = FM_MEM_EVENT_FUNC
  PL1A_L_GPLLT_FB  = TP_CPLD1_PL1A_L_GPLLT_FB
  GND(4)  = GND
  VCCIO0(3)  = P3V3_STBY
  PT12A  = RST_PCIE_CPU_DEV0_N
  PT13D  = FM_FORCE_ADR_N
  PT17C  = TP_CPLD1_PT17C
  PT18B  = RST_PCIE_MIDPLANE_N
  PT20A  = TP_CPLD1_PT20A
  PT21D  = FM_CPU0_AND_CPU1_MCP_PRES
  VCCIO0(1)  = P3V3_STBY
  GND(5)  = GND
  PR1A  = PWRGD_SYS_PWROK
  PR2D  = PWRGD_P1V8MCP_CPU0
  PR2A  = PWRGD_P1V8MCP_CPU1
  PL3A_PCLKT5_0  = CLK_32K_SUSCLK_PLD
  PL2A_L_GPLLT_IN  = FM_CPU_CATERR_DLY_LVT3_N
  PL2B_L_GPLLC_IN  = TP_CPLD1_PL2B_L_GPLLC_IN
  VCCIO5(0)  = P3V3_STBY
  GND(6)  = GND
  PT13C  = FM_CPU1_FIVR_FAULT_LVT3_N
  PT12B  = PWRGD_P1V15_BMC_STBY
  PT16B  = TP_CPLD1_PT16B
  PT17D  = FM_SLP_SUS_N
  PT20B  = TP_CPLD1_PT20B
  PT19D  = TP_CPLD1_PT19D
  GND(7)  = GND
  VCCIO1(0)  = P3V3_STBY
  PR2B  = FM_CPLD_ADR_TRIGGER_N
  PR1B  = RST_PLTRST_N
  PR3A  = FM_P1V8MCP_CPU0_EN
  PL4B  = FM_CPU0_PROC_ID0
  PL3B_PCLKC5_0  = FM_CPU0_PKGID0
  PL4A  = FM_CPU0_PROC_ID1
  PL3C  = PU_RST_PERST_BIT0
  PL5C  = FM_CPU0_FIVR_FAULT_LVT3_N
  GND(8)  = GND
  PT16A  = FM_PLD_DEBUG_MODE_N
  PT18A  = SGPIO_BMC_DIN_R
  PT19C  = FM_PS_EN
  PT21C  = FM_CPU1_CD_PRES_N
  GND(9)  = GND
  PR4C  = FM_P1V8MCP_CPU1_EN
  PR3C  = PWRGD_CPUPWRGD
  PR4A  = RST_BMC_SYSRST_BTN_OUT_B_R1_N
  PR3B  = FM_CPU0_MCP_CLK_EN_N
  PR4B  = FM_CPU1_MCP_CLK_EN_N
  PL6A  = FM_SLPS3_N
  PL5A  = FM_CPU0_PKGID2
  PL5B  = FM_CPU0_PKGID1
  PL4D  = RST_RSMRST_R_N
  PL4C  = FM_DEBUG_RST_BTN_N
  PL3D  = FM_PWR_BTN_R2_N
  VCC(4)  = P3V3_STBY
  VCCIO0(0)  = P3V3_STBY
  VCCIO0(2)  = P3V3_STBY
  VCC(5)  = P3V3_STBY
  PR5C  = FM_WBG_PRSNT_N
  PR3D  = FM_CPU0_THERMTRIP_LATCH_LVT3_N
  PR4D  = FM_CPU1_FIVR_FAULT_LVT3
  PR5B  = FM_CPU1_THERMTRIP_LVT3_N
  PR5A  = FM_UV_ADR_TRIGGER_N
  PR6A  = FM_FAST_PROCHOT_THROTTLE_IN_N
  PL7B  = RST_PCIE_CPU_DEV3_N
  PL6B  = FM_PVCCMCP_CPU0_EN
  PL7A  = RST_PCIE_CPU_DEV2_N
  PL6C  = FM_MP_PS_FAIL_N
  PL9C  = NC
  PL5D  = PWRGD_P3V3
  VCCIO4(1)  = P3V3_STBY
  GND(10)  = GND
  GND(11)  = GND
  VCCIO1(1)  = P3V3_STBY
  PR9C  = TP_CPLD1_PR9C
  PR5D  = FM_UV_ADR_TRIGGER_EN
  PR6C  = FM_PVDDQ_GHJ_EN
  PR7A_PCLKT1_0  = TP_CPLD1_PR7A_PCLKT1_0
  PR6B  = FM_PVDDQ_KLM_EN
  PR7B_PCLKC1_0  = TP_CPLD1_PR7B_PCLKC1_0
  PL7C_PCLKT4_0  = SGPIO_BMC_CLK
  PL9A  = SGPIO_BMC_DOUT
  PL7D_PCLKC4_0  = TP_CPLD1_PL7D_PCLKT4_0
  PL9D  = NC
  PL10C  = UART_BMC_RXD5
  PL6D  = PWRGD_P5V
  VCCIO4(0)  = P3V3_STBY
  GND(12)  = GND
  GND(13)  = GND
  VCCIO1(2)  = P3V3_STBY
  PR10C  = TP_CPLD1_PR10C
  PR6D  = FM_FAST_PROCHOT_THROTTLE_DLY_N
  PR9D  = TP_CPLD1_PR9D
  PR7D  = TP_CPLD1_PR7D
  PR9A  = TP_CPLD1_PR9A
  PR7C  = TP_CPLD1_PR7C
  PL9B  = FM_PVCCIOMCP_CPU0_EN
  PL10B  = SP1_BMC_HOST_UART_TX
  PL10A  = SP1_BMC_HOST_UART_RX
  PL11C  = SGPIO_BMC_LD_N
  PL12C  = PWRGD_PVCCIN_CPU0
  PL10D  = UART_BMC_TXD5
  VCC(6)  = P3V3_STBY
  VCCIO2(2)  = P3V3_STBY
  VCCIO2(0)  = P3V3_STBY
  VCC(7)  = P3V3_STBY
  PR12C  = RST_PLTRST_BUF_N
  PR11D  = FM_MEM_THERM_EVENT_PCH_N
  PR11C  = FM_MEM_THERM_EVENT_LVT3_N
  PR10A  = FM_PVDDQ_ABC_EN
  PR10B  = FM_PVDDQ_DEF_EN
  PR9B  = PU_FAB2_MARKER_CPLD
  PL11A  = PWRGD_PVSA_CPU0
  PL12A_PCLKT3_0  = CLK_25M_CPLD
  PL11B  = TP_CPLD1_PL11A
  PL12D  = PWRGD_PVCCMCP_CPU1
  PL11D  = PWRGD_CPU0_LVC3
  GND(14)  = GND
  PB8D  = FM_OC0_USB_N
  PB11D  = PWRGD_PVCCIO_CPU0
  PB12D  = FM_IE_DISABLE_N
  PB18D  = FM_SOL_UART_CH_SEL
  GND(15)  = GND
  PR10D  = PWRGD_P3V3_STBY
  PR12D  = TP_CPLD1_PR12D
  PR11B  = TP_CPLD1_PR11B
  PR12A  = FM_THERMTRIP_DLY
  PR11A  = PWRGD_PVCCIO_CPU1
  PL12B_PCLKC3_0  = RST_RSMRST_DLY
  PL14A  = PWRGD_PVPP_GHJ
  PL13A  = RST_PCIE_RISER1_PERST_N
  VCCIO3(0)  = P3V3_STBY
  GND(16)  = GND
  PB11C  = PWRGD_PVPP_DEF
  PB9C  = FM_PVCCIO_CPU0_EN
  PB16C  = FM_PVCCMCP_CPU1_EN
  PB18C  = FM_CPLD_UART_CH_LOCK_N
  PB21C  = PWRGD_CPU1_LVC3
  PB19D  = XDP_PWRGD_RST_N
  GND(17)  = GND
  VCCIO1(3)  = P3V3_STBY
  PR13A  = FM_CPU1_PROC_ID1
  PR13B  = FM_CPU1_PROC_ID0
  PR12B  = FM_CPU0_FIVR_FAULT_LVT3
  PL13B  = PWRGD_PVCCIN_CPU1
  PL13C  = PWRGD_PVPP_KLM
  PL14B  = RST_CD_CPU0_POR_N
  GND(18)  = GND
  VCCIO2(3)  = P3V3_STBY
  PB8C  = PWRGD_PVCCIOMCP_CPU0
  PB9D  = PWRGD_PVPP_ABC
  PB12C  = FM_156M_CPU1_BRD_OSC_EN
  PB16D  = FM_CPLD_BMC_PWRDN_N
  PB19C  = RST_CPU1_LVC3_R1_N
  PB21D  = XDP_SYSPWROK
  VCCIO2(1)  = P3V3_STBY
  GND(19)  = GND
  PR14B  = FM_CPU1_VRM_OSC_EN
  PR13C  = FM_CPU0_THERMTRIP_LVT3_N
  PR14A  = FM_PVCCIN_PVCCSA_CPU1_EN_LVC1
  PL13D  = FM_GLOBAL_RST_WARN_N
  PL14D  = FM_UART_ALERT_N
  GND(20)  = GND
  PB3A  = FM_CPU1_RC_EN
  PB5B  = PWRGD_PVCCMCP_CPU0
  PB8A_MCLK_CCLK  = TP_CPLD1_PB8A_MCLK_CCLK
  PB9B  = FM_PVCCIOMCP_CPU1_EN
  PB12A  = PWRGD_PVNN_P1V05_PCH
  PB16B_PCLKC2_1  = TP_CPLD1_PB16B_PCLKC2_1
  PB19A  = RST_CD_CPU1_POR_N
  PB21B  = FM_UARTSW_MSB_N
  PB24A  = FM_CPU1_PKGID1
  PB25B_SI_SISPI  = TP_CPLD1_PB25B_SI_SISPI
  GND(21)  = GND
  PR14C  = FM_PVPP_CPU0_EN
  PR13D  = FM_PVPP_CPU1_EN
  PL14C  = FM_BMC_CPLD_GPO
  GND(22)  = GND
  PB3D  = FM_CPU0_RC_EN
  PB6D  = FM_BMC_CPLD_MP_RST_N
  PB5A_CSSPIN  = TP_CPLD1_PB5A_CSSPIN
  PB6B  = RST_PCIE_M2_DEV_N
  PB9A  = PWRGD_PVTT_CPU1
  PB11B_PCLKC2_0  = FM_CPLD_USB_P0_EN_N
  PB18A  = FM_UARTSW_LSB_N
  PB19B  = RST_CPU0_LVC3_R1_N
  PB22A  = FM_DB1200ZL_BCLKS_EN_N
  PB25A_SN  = FM_CPU1_PKGID0
  PB22C  = FM_CPU0_VRM_OSC_EN
  PB25D  = FM_CPU_CATERR_LVT3_N
  GND(23)  = GND
  PR14D  = FM_P12V_MAIN_SW_EN
  VCC(2)  = P3V3_STBY
  PB3C  = FM_ADR_MODE_SEL
  PB6C  = FM_DIS_ADR_DLY
  PB3B  = PWRGD_PVSA_CPU1
  PB6A  = PWRGD_PVCCIOMCP_CPU1
  PB8B_SO_SPISO  = TP_CPLD1_PB8B_SO_SPISO
  PB11A_PCLKT2_0  = FM_PVCCIO_CPU1_EN
  PB12B  = FM_CPLD_DBG_PWR_EN_N
  PB16A_PCLKT2_1  = TP_CPLD1_PB16A_PCLKT2_1
  PB18B  = FM_156M_CPU0_BRD_OSC_EN
  PB21A  = FM_CPU1_PKGID2
  PB22B  = FM_CPU1_SKTOCC_LVT3_N
  PB24B  = FM_CPU_MSMI_LVT3_N
  PB22D  = FM_CPU0_SKTOCC_LVT3_N
  PB25C  = PWRGD_DRAMPWRGD
  VCC(3)  = P3V3_STBY

(kicad_pcb
	(version 20260206)
	(generator "pcbnew")
	(generator_version "10.0")
	(general
		(thickness 1.6)
		(legacy_teardrops no)
	)
	(paper "A4")
	(title_block
		(title "Wiwynn_Tioga_Pass_MB.brd")
		(comment 1 "Tioga Pass / footprint 2035 of 4770 (U8D7), pads 90-134 of 256")
	)
	(layers
		(0 "F.Cu" signal "TOP")
		(4 "In1.Cu" signal "L2GND")
		(6 "In2.Cu" signal "L3")
		(8 "In3.Cu" signal "L4GND")
		(10 "In4.Cu" signal "L5")
		(12 "In5.Cu" signal "L6GND")
		(14 "In6.Cu" signal "L7VCC")
		(16 "In7.Cu" signal "L8VCC")
		(18 "In8.Cu" signal "L9GND")
		(20 "In9.Cu" signal "L10")
		(22 "In10.Cu" signal "L11GND")
		(24 "In11.Cu" signal "L12")
		(26 "In12.Cu" signal "L13GND")
		(2 "B.Cu" signal "BOTTOM")
		(9 "F.Adhes" user "F.Adhesive")
		(11 "B.Adhes" user "B.Adhesive")
		(13 "F.Paste" user "Package Geometry/Pastemask Top")
		(15 "B.Paste" user "Package Geometry/Pastemask Bottom")
		(5 "F.SilkS" user "Ref Des/Silkscreen Top")
		(7 "B.SilkS" user "Ref Des/Silkscreen Bottom")
		(1 "F.Mask" user "Board Geometry/Soldermask Top")
		(3 "B.Mask" user "Board Geometry/Soldermask Bottom")
		(17 "Dwgs.User" user "User.Drawings")
		(19 "Cmts.User" user "User.Comments")
		(21 "Eco1.User" user "User.Eco1")
		(23 "Eco2.User" user "User.Eco2")
		(25 "Edge.Cuts" user "Board Geometry/Outline")
		(27 "Margin" user)
		(31 "F.CrtYd" user "Package Geometry/Place Bound Top")
		(29 "B.CrtYd" user "Package Geometry/Place Bound Bottom")
		(35 "F.Fab" user "Ref Des/Assembly Top")
		(33 "B.Fab" user "Ref Des/Assembly Bottom")
	)
	(footprint ""
		(layer "F.Cu")
		(at 372.745 -74.295 180)
		(property "Reference" "U8D7"
			(at -0.635 -8.28167 0)
			(unlocked yes)
			(layer "F.SilkS")
			(effects
				(font
					(size 0.7874 0.5842)
					(thickness 0.1524)
				)
			)
		)
		(property "Value" ""
			(at 0 0 180)
			(layer "F.Fab")
			(effects
				(font
					(size 1.27 1.27)
				)
			)
		)
		(duplicate_pad_numbers_are_jumpers no)
		(pad "F10" smd circle
			(at 1.199896 -1.999996 180)
			(size 0.3556 0.3556)
			(layers "F.Cu" "F.Mask" "F.Paste")
			(net "FM_CPU1_CD_PRES_N")
		)
		(pad "F11" smd circle
			(at 1.999996 -1.999996 180)
			(size 0.3556 0.3556)
			(layers "F.Cu" "F.Mask" "F.Paste")
			(net "GND")
		)
		(pad "F12" smd circle
			(at 2.800096 -1.999996 180)
			(size 0.3556 0.3556)
			(layers "F.Cu" "F.Mask" "F.Paste")
			(net "FM_P1V8MCP_CPU1_EN")
		)
		(pad "F13" smd circle
			(at 3.599942 -1.999996 180)
			(size 0.3556 0.3556)
			(layers "F.Cu" "F.Mask" "F.Paste")
			(net "PWRGD_CPUPWRGD")
		)
		(pad "F14" smd circle
			(at 4.400042 -1.999996 180)
			(size 0.3556 0.3556)
			(layers "F.Cu" "F.Mask" "F.Paste")
			(net "RST_BMC_SYSRST_BTN_OUT_B_R1_N")
		)
		(pad "F15" smd circle
			(at 5.199888 -1.999996 180)
			(size 0.3556 0.3556)
			(layers "F.Cu" "F.Mask" "F.Paste")
			(net "FM_CPU0_MCP_CLK_EN_N")
		)
		(pad "F16" smd circle
			(at 5.999988 -1.999996 180)
			(size 0.3556 0.3556)
			(layers "F.Cu" "F.Mask" "F.Paste")
			(net "FM_CPU1_MCP_CLK_EN_N")
		)
		(pad "G1" smd circle
			(at -5.999988 -1.199896 180)
			(size 0.3556 0.3556)
			(layers "F.Cu" "F.Mask" "F.Paste")
			(net "FM_SLPS3_N")
		)
		(pad "G2" smd circle
			(at -5.199888 -1.199896 180)
			(size 0.3556 0.3556)
			(layers "F.Cu" "F.Mask" "F.Paste")
			(net "FM_CPU0_PKGID2")
		)
		(pad "G3" smd circle
			(at -4.400042 -1.199896 180)
			(size 0.3556 0.3556)
			(layers "F.Cu" "F.Mask" "F.Paste")
			(net "FM_CPU0_PKGID1")
		)
		(pad "G4" smd circle
			(at -3.599942 -1.199896 180)
			(size 0.3556 0.3556)
			(layers "F.Cu" "F.Mask" "F.Paste")
			(net "RST_RSMRST_R_N")
		)
		(pad "G5" smd circle
			(at -2.800096 -1.199896 180)
			(size 0.3556 0.3556)
			(layers "F.Cu" "F.Mask" "F.Paste")
			(net "FM_DEBUG_RST_BTN_N")
		)
		(pad "G6" smd circle
			(at -1.999996 -1.199896 180)
			(size 0.3556 0.3556)
			(layers "F.Cu" "F.Mask" "F.Paste")
			(net "FM_PWR_BTN_R2_N")
		)
		(pad "G7" smd circle
			(at -1.199896 -1.199896 180)
			(size 0.3556 0.3556)
			(layers "F.Cu" "F.Mask" "F.Paste")
			(net "P3V3_STBY")
		)
		(pad "G8" smd circle
			(at -0.40005 -1.199896 180)
			(size 0.3556 0.3556)
			(layers "F.Cu" "F.Mask" "F.Paste")
			(net "P3V3_STBY")
		)
		(pad "G9" smd circle
			(at 0.40005 -1.199896 180)
			(size 0.3556 0.3556)
			(layers "F.Cu" "F.Mask" "F.Paste")
			(net "P3V3_STBY")
		)
		(pad "G10" smd circle
			(at 1.199896 -1.199896 180)
			(size 0.3556 0.3556)
			(layers "F.Cu" "F.Mask" "F.Paste")
			(net "P3V3_STBY")
		)
		(pad "G11" smd circle
			(at 1.999996 -1.199896 180)
			(size 0.3556 0.3556)
			(layers "F.Cu" "F.Mask" "F.Paste")
			(net "FM_WBG_PRSNT_N")
		)
		(pad "G12" smd circle
			(at 2.800096 -1.199896 180)
			(size 0.3556 0.3556)
			(layers "F.Cu" "F.Mask" "F.Paste")
			(net "FM_CPU0_THERMTRIP_LATCH_LVT3_N")
		)
		(pad "G13" smd circle
			(at 3.599942 -1.199896 180)
			(size 0.3556 0.3556)
			(layers "F.Cu" "F.Mask" "F.Paste")
			(net "FM_CPU1_FIVR_FAULT_LVT3")
		)
		(pad "G14" smd circle
			(at 4.400042 -1.199896 180)
			(size 0.3556 0.3556)
			(layers "F.Cu" "F.Mask" "F.Paste")
			(net "FM_CPU1_THERMTRIP_LVT3_N")
		)
		(pad "G15" smd circle
			(at 5.199888 -1.199896 180)
			(size 0.3556 0.3556)
			(layers "F.Cu" "F.Mask" "F.Paste")
			(net "FM_UV_ADR_TRIGGER_N")
		)
		(pad "G16" smd circle
			(at 5.999988 -1.199896 180)
			(size 0.3556 0.3556)
			(layers "F.Cu" "F.Mask" "F.Paste")
			(net "FM_FAST_PROCHOT_THROTTLE_IN_N")
		)
		(pad "H1" smd circle
			(at -5.999988 -0.40005 180)
			(size 0.3556 0.3556)
			(layers "F.Cu" "F.Mask" "F.Paste")
			(net "RST_PCIE_CPU_DEV3_N")
		)
		(pad "H2" smd circle
			(at -5.199888 -0.40005 180)
			(size 0.3556 0.3556)
			(layers "F.Cu" "F.Mask" "F.Paste")
			(net "FM_PVCCMCP_CPU0_EN")
		)
		(pad "H3" smd circle
			(at -4.400042 -0.40005 180)
			(size 0.3556 0.3556)
			(layers "F.Cu" "F.Mask" "F.Paste")
			(net "RST_PCIE_CPU_DEV2_N")
		)
		(pad "H4" smd circle
			(at -3.599942 -0.40005 180)
			(size 0.3556 0.3556)
			(layers "F.Cu" "F.Mask" "F.Paste")
			(net "FM_MP_PS_FAIL_N")
		)
		(pad "H5" smd circle
			(at -2.800096 -0.40005 180)
			(size 0.3556 0.3556)
			(layers "F.Cu" "F.Mask" "F.Paste")
			(net "Net_480")
		)
		(pad "H6" smd circle
			(at -1.999996 -0.40005 180)
			(size 0.3556 0.3556)
			(layers "F.Cu" "F.Mask" "F.Paste")
			(net "PWRGD_P3V3")
		)
		(pad "H7" smd circle
			(at -1.199896 -0.40005 180)
			(size 0.3556 0.3556)
			(layers "F.Cu" "F.Mask" "F.Paste")
			(net "P3V3_STBY")
		)
		(pad "H8" smd circle
			(at -0.40005 -0.40005 180)
			(size 0.3556 0.3556)
			(layers "F.Cu" "F.Mask" "F.Paste")
			(net "GND")
		)
		(pad "H9" smd circle
			(at 0.40005 -0.40005 180)
			(size 0.3556 0.3556)
			(layers "F.Cu" "F.Mask" "F.Paste")
			(net "GND")
		)
		(pad "H10" smd circle
			(at 1.199896 -0.40005 180)
			(size 0.3556 0.3556)
			(layers "F.Cu" "F.Mask" "F.Paste")
			(net "P3V3_STBY")
		)
		(pad "H11" smd circle
			(at 1.999996 -0.40005 180)
			(size 0.3556 0.3556)
			(layers "F.Cu" "F.Mask" "F.Paste")
			(net "TP_CPLD1_PR9C")
		)
		(pad "H12" smd circle
			(at 2.800096 -0.40005 180)
			(size 0.3556 0.3556)
			(layers "F.Cu" "F.Mask" "F.Paste")
			(net "FM_UV_ADR_TRIGGER_EN")
		)
		(pad "H13" smd circle
			(at 3.599942 -0.40005 180)
			(size 0.3556 0.3556)
			(layers "F.Cu" "F.Mask" "F.Paste")
			(net "FM_PVDDQ_GHJ_EN")
		)
		(pad "H14" smd circle
			(at 4.400042 -0.40005 180)
			(size 0.3556 0.3556)
			(layers "F.Cu" "F.Mask" "F.Paste")
			(net "TP_CPLD1_PR7A_PCLKT1_0")
		)
		(pad "H15" smd circle
			(at 5.199888 -0.40005 180)
			(size 0.3556 0.3556)
			(layers "F.Cu" "F.Mask" "F.Paste")
			(net "FM_PVDDQ_KLM_EN")
		)
		(pad "H16" smd circle
			(at 5.999988 -0.40005 180)
			(size 0.3556 0.3556)
			(layers "F.Cu" "F.Mask" "F.Paste")
			(net "TP_CPLD1_PR7B_PCLKC1_0")
		)
		(pad "J1" smd circle
			(at -5.999988 0.40005 180)
			(size 0.3556 0.3556)
			(layers "F.Cu" "F.Mask" "F.Paste")
			(net "SGPIO_BMC_CLK")
		)
		(pad "J2" smd circle
			(at -5.199888 0.40005 180)
			(size 0.3556 0.3556)
			(layers "F.Cu" "F.Mask" "F.Paste")
			(net "SGPIO_BMC_DOUT")
		)
		(pad "J3" smd circle
			(at -4.400042 0.40005 180)
			(size 0.3556 0.3556)
			(layers "F.Cu" "F.Mask" "F.Paste")
			(net "TP_CPLD1_PL7D_PCLKT4_0")
		)
		(pad "J4" smd circle
			(at -3.599942 0.40005 180)
			(size 0.3556 0.3556)
			(layers "F.Cu" "F.Mask" "F.Paste")
			(net "Net_481")
		)
		(pad "J5" smd circle
			(at -2.800096 0.40005 180)
			(size 0.3556 0.3556)
			(layers "F.Cu" "F.Mask" "F.Paste")
			(net "UART_BMC_RXD5")
		)
		(pad "J6" smd circle
			(at -1.999996 0.40005 180)
			(size 0.3556 0.3556)
			(layers "F.Cu" "F.Mask" "F.Paste")
			(net "PWRGD_P5V")
		)
	)
)
